# T6G (Grand Teton) — schematic netlist excerpt (pin names and nets, part order shuffled) for the footprints in the layout excerpt that follows; sources: Cadence DE-HDL packaged netlist, KiCad conversion of 04192023_DAF0TMB3IC0_F0TG_MB_C_brd_V02_OCP.brd

PC423_C1P1_5  Q_CAP  2.2UF 10V 10% X6S  pkg C0402  page 220 : A = PVDDCR_CPU1_P1_PVCC ; B = GND
R3289  Q_RES  1K 1% EMPTY  pkg 0402LF  page 111 : A = P3V3_AUX ; B = FM_P2E_SWA

(kicad_pcb
	(version 20260206)
	(generator "pcbnew")
	(generator_version "10.0")
	(general
		(thickness 1.6)
		(legacy_teardrops no)
	)
	(paper "A4")
	(title_block
		(title "04192023_DAF0TMB3IC0_F0TG_MB_C_brd_V02_OCP.brd")
		(comment 1 "Grand Teton / footprints 2126-2127 of 8354")
	)
	(layers
		(0 "F.Cu" signal "TOP")
		(4 "In1.Cu" signal "GND")
		(6 "In2.Cu" signal "IN1")
		(8 "In3.Cu" signal "GND1")
		(10 "In4.Cu" signal "IN2")
		(12 "In5.Cu" signal "GND2")
		(14 "In6.Cu" signal "IN3")
		(16 "In7.Cu" signal "GND3")
		(18 "In8.Cu" signal "VCC")
		(20 "In9.Cu" signal "VCC1")
		(22 "In10.Cu" signal "GND4")
		(24 "In11.Cu" signal "IN4")
		(26 "In12.Cu" signal "GND5")
		(28 "In13.Cu" signal "IN5")
		(30 "In14.Cu" signal "GND6")
		(32 "In15.Cu" signal "IN6")
		(34 "In16.Cu" signal "GND7")
		(2 "B.Cu" signal "BOTTOM")
		(9 "F.Adhes" user "F.Adhesive")
		(11 "B.Adhes" user "B.Adhesive")
		(13 "F.Paste" user "Package Geometry/Pastemask Top")
		(15 "B.Paste" user "Package Geometry/Pastemask Bottom")
		(5 "F.SilkS" user "Ref Des/Silkscreen Top")
		(7 "B.SilkS" user "Ref Des/Silkscreen Bottom")
		(1 "F.Mask" user "Board Geometry/Soldermask Top")
		(3 "B.Mask" user "Board Geometry/Soldermask Bottom")
		(17 "Dwgs.User" user "User.Drawings")
		(19 "Cmts.User" user "User.Comments")
		(21 "Eco1.User" user "User.Eco1")
		(23 "Eco2.User" user "User.Eco2")
		(25 "Edge.Cuts" user "Board Geometry/Outline")
		(27 "Margin" user)
		(31 "F.CrtYd" user "Package Geometry/Place Bound Top")
		(29 "B.CrtYd" user "Package Geometry/Place Bound Bottom")
		(35 "F.Fab" user "Ref Des/Assembly Top")
		(33 "B.Fab" user "Ref Des/Assembly Bottom")
	)
	(footprint ""
		(layer "F.Cu")
		(at 34.633662 -419.249098 90)
		(property "Reference" "R3289"
			(at 0 0 90)
			(layer "F.SilkS")
			(hide yes)
			(effects
				(font
					(size 1.27 1.27)
				)
			)
		)
		(property "Value" ""
			(at 0 0 90)
			(layer "F.Fab")
			(effects
				(font
					(size 1.27 1.27)
				)
			)
		)
		(duplicate_pad_numbers_are_jumpers no)
		(fp_line
			(start 0.7874 -0.4064)
			(end 0.7874 0.4064)
			(stroke
				(width 0.1524)
				(type default)
			)
			(layer "F.SilkS")
		)
		(fp_line
			(start -0.7874 -0.4064)
			(end 0.7874 -0.4064)
			(stroke
				(width 0.1524)
				(type default)
			)
			(layer "F.SilkS")
		)
		(fp_line
			(start 0.7874 0.4064)
			(end -0.7874 0.4064)
			(stroke
				(width 0.1524)
				(type default)
			)
			(layer "F.SilkS")
		)
		(fp_line
			(start -0.7874 0.4064)
			(end -0.7874 -0.4064)
			(stroke
				(width 0.1524)
				(type default)
			)
			(layer "F.SilkS")
		)
		(fp_line
			(start -0.12065 -0.305054)
			(end -0.12065 -0.2794)
			(stroke
				(width 0.1)
				(type default)
			)
			(layer "F.Fab")
		)
		(fp_line
			(start -0.67945 -0.305054)
			(end -0.12065 -0.305054)
			(stroke
				(width 0.1)
				(type default)
			)
			(layer "F.Fab")
		)
		(fp_line
			(start 0.67945 -0.3048)
			(end 0.67945 0.3048)
			(stroke
				(width 0.1)
				(type default)
			)
			(layer "F.Fab")
		)
		(fp_line
			(start 0.12065 -0.3048)
			(end 0.67945 -0.3048)
			(stroke
				(width 0.1)
				(type default)
			)
			(layer "F.Fab")
		)
		(fp_line
			(start 0.12065 -0.2794)
			(end 0.12065 -0.3048)
			(stroke
				(width 0.1)
				(type default)
			)
			(layer "F.Fab")
		)
		(fp_line
			(start -0.12065 -0.2794)
			(end 0.12065 -0.2794)
			(stroke
				(width 0.1)
				(type default)
			)
			(layer "F.Fab")
		)
		(fp_line
			(start 0.120396 0.2794)
			(end -0.12065 0.2794)
			(stroke
				(width 0.1)
				(type default)
			)
			(layer "F.Fab")
		)
		(fp_line
			(start -0.12065 0.2794)
			(end -0.12065 0.3048)
			(stroke
				(width 0.1)
				(type default)
			)
			(layer "F.Fab")
		)
		(fp_line
			(start 0.67945 0.3048)
			(end 0.120396 0.3048)
			(stroke
				(width 0.1)
				(type default)
			)
			(layer "F.Fab")
		)
		(fp_line
			(start 0.120396 0.3048)
			(end 0.120396 0.2794)
			(stroke
				(width 0.1)
				(type default)
			)
			(layer "F.Fab")
		)
		(fp_line
			(start -0.12065 0.3048)
			(end -0.67945 0.3048)
			(stroke
				(width 0.1)
				(type default)
			)
			(layer "F.Fab")
		)
		(fp_line
			(start -0.67945 0.3048)
			(end -0.67945 -0.305054)
			(stroke
				(width 0.1)
				(type default)
			)
			(layer "F.Fab")
		)
		(pad "1" smd circle
			(at -0.40005 0 90)
			(size 0 0)
			(layers "F.Cu" "F.Mask" "F.Paste")
			(net "P3V3_AUX")
		)
		(pad "2" smd circle
			(at 0.40005 0 90)
			(size 0 0)
			(layers "F.Cu" "F.Mask" "F.Paste")
			(net "FM_P2E_SWA")
		)
	)
	(footprint ""
		(layer "F.Cu")
		(at 91.770454 -335.027524 -90)
		(property "Reference" "PC423_C1P1_5"
			(at 0 0 270)
			(layer "F.SilkS")
			(hide yes)
			(effects
				(font
					(size 1.27 1.27)
				)
			)
		)
		(property "Value" ""
			(at 0 0 270)
			(layer "F.Fab")
			(effects
				(font
					(size 1.27 1.27)
				)
			)
		)
		(duplicate_pad_numbers_are_jumpers no)
		(fp_line
			(start -0.7874 0.4064)
			(end -0.7874 -0.4064)
			(stroke
				(width 0.1524)
				(type default)
			)
			(layer "F.SilkS")
		)
		(fp_line
			(start 0.7874 0.4064)
			(end -0.7874 0.4064)
			(stroke
				(width 0.1524)
				(type default)
			)
			(layer "F.SilkS")
		)
		(fp_line
			(start -0.7874 -0.4064)
			(end 0.7874 -0.4064)
			(stroke
				(width 0.1524)
				(type default)
			)
			(layer "F.SilkS")
		)
		(fp_line
			(start 0.7874 -0.4064)
			(end 0.7874 0.4064)
			(stroke
				(width 0.1524)
				(type default)
			)
			(layer "F.SilkS")
		)
		(fp_line
			(start -0.67945 0.3048)
			(end -0.67945 -0.305054)
			(stroke
				(width 0.1)
				(type default)
			)
			(layer "F.Fab")
		)
		(fp_line
			(start -0.12065 0.3048)
			(end -0.67945 0.3048)
			(stroke
				(width 0.1)
				(type default)
			)
			(layer "F.Fab")
		)
		(fp_line
			(start 0.120396 0.3048)
			(end 0.120396 0.2794)
			(stroke
				(width 0.1)
				(type default)
			)
			(layer "F.Fab")
		)
		(fp_line
			(start 0.67945 0.3048)
			(end 0.120396 0.3048)
			(stroke
				(width 0.1)
				(type default)
			)
			(layer "F.Fab")
		)
		(fp_line
			(start -0.12065 0.2794)
			(end -0.12065 0.3048)
			(stroke
				(width 0.1)
				(type default)
			)
			(layer "F.Fab")
		)
		(fp_line
			(start 0.120396 0.2794)
			(end -0.12065 0.2794)
			(stroke
				(width 0.1)
				(type default)
			)
			(layer "F.Fab")
		)
		(fp_line
			(start -0.12065 -0.2794)
			(end 0.12065 -0.2794)
			(stroke
				(width 0.1)
				(type default)
			)
			(layer "F.Fab")
		)
		(fp_line
			(start 0.12065 -0.2794)
			(end 0.12065 -0.3048)
			(stroke
				(width 0.1)
				(type default)
			)
			(layer "F.Fab")
		)
		(fp_line
			(start 0.12065 -0.3048)
			(end 0.67945 -0.3048)
			(stroke
				(width 0.1)
				(type default)
			)
			(layer "F.Fab")
		)
		(fp_line
			(start 0.67945 -0.3048)
			(end 0.67945 0.3048)
			(stroke
				(width 0.1)
				(type default)
			)
			(layer "F.Fab")
		)
		(fp_line
			(start -0.67945 -0.305054)
			(end -0.12065 -0.305054)
			(stroke
				(width 0.1)
				(type default)
			)
			(layer "F.Fab")
		)
		(fp_line
			(start -0.12065 -0.305054)
			(end -0.12065 -0.2794)
			(stroke
				(width 0.1)
				(type default)
			)
			(layer "F.Fab")
		)
		(pad "1" smd circle
			(at -0.40005 0 270)
			(size 0 0)
			(layers "F.Cu" "F.Mask" "F.Paste")
			(net "PVDDCR_CPU1_P1_PVCC")
		)
		(pad "2" smd circle
			(at 0.40005 0 270)
			(size 0 0)
			(layers "F.Cu" "F.Mask" "F.Paste")
			(net "GND")
		)
	)
)
